# T6G (Grand Teton) — schematic netlist excerpt (pin names and nets, part order shuffled) for the footprints in the layout excerpt that follows; sources: Cadence DE-HDL packaged netlist, KiCad conversion of 04192023_DAF0TMB3IC0_F0TG_MB_C_brd_V02_OCP.brd

R924  Q_RES  4.7K 5% CHIP  pkg 0201LF  page 353 : A = JTAG_TEST_MODE_RT_CPU1_P3 ; B = GND
R823  Q_RES  10K 5% EMPTY  pkg 0402LF  page 164 : A = P3V3_AUX ; B = UART_CPU0_SCM_LVC3_UART1_R_RX
R3973  Q_RES  0 5% CHIP  pkg 0402LF  page 146 : A = P3V3_E1S_PWRGD_0 ; B = P3V3_E1S_PWRGD_0_R

(kicad_pcb
	(version 20260206)
	(generator "pcbnew")
	(generator_version "10.0")
	(general
		(thickness 1.6)
		(legacy_teardrops no)
	)
	(paper "A4")
	(title_block
		(title "04192023_DAF0TMB3IC0_F0TG_MB_C_brd_V02_OCP.brd")
		(comment 1 "Grand Teton / footprints 2731-2733 of 8354")
	)
	(layers
		(0 "F.Cu" signal "TOP")
		(4 "In1.Cu" signal "GND")
		(6 "In2.Cu" signal "IN1")
		(8 "In3.Cu" signal "GND1")
		(10 "In4.Cu" signal "IN2")
		(12 "In5.Cu" signal "GND2")
		(14 "In6.Cu" signal "IN3")
		(16 "In7.Cu" signal "GND3")
		(18 "In8.Cu" signal "VCC")
		(20 "In9.Cu" signal "VCC1")
		(22 "In10.Cu" signal "GND4")
		(24 "In11.Cu" signal "IN4")
		(26 "In12.Cu" signal "GND5")
		(28 "In13.Cu" signal "IN5")
		(30 "In14.Cu" signal "GND6")
		(32 "In15.Cu" signal "IN6")
		(34 "In16.Cu" signal "GND7")
		(2 "B.Cu" signal "BOTTOM")
		(9 "F.Adhes" user "F.Adhesive")
		(11 "B.Adhes" user "B.Adhesive")
		(13 "F.Paste" user "Package Geometry/Pastemask Top")
		(15 "B.Paste" user "Package Geometry/Pastemask Bottom")
		(5 "F.SilkS" user "Ref Des/Silkscreen Top")
		(7 "B.SilkS" user "Ref Des/Silkscreen Bottom")
		(1 "F.Mask" user "Board Geometry/Soldermask Top")
		(3 "B.Mask" user "Board Geometry/Soldermask Bottom")
		(17 "Dwgs.User" user "User.Drawings")
		(19 "Cmts.User" user "User.Comments")
		(21 "Eco1.User" user "User.Eco1")
		(23 "Eco2.User" user "User.Eco2")
		(25 "Edge.Cuts" user "Board Geometry/Outline")
		(27 "Margin" user)
		(31 "F.CrtYd" user "Package Geometry/Place Bound Top")
		(29 "B.CrtYd" user "Package Geometry/Place Bound Bottom")
		(35 "F.Fab" user "Ref Des/Assembly Top")
		(33 "B.Fab" user "Ref Des/Assembly Bottom")
	)
	(footprint ""
		(layer "F.Cu")
		(at 367.931446 -30.135322 90)
		(property "Reference" "R823"
			(at 0 0 90)
			(layer "F.SilkS")
			(hide yes)
			(effects
				(font
					(size 1.27 1.27)
				)
			)
		)
		(property "Value" ""
			(at 0 0 90)
			(layer "F.Fab")
			(effects
				(font
					(size 1.27 1.27)
				)
			)
		)
		(duplicate_pad_numbers_are_jumpers no)
		(fp_line
			(start 0.7874 -0.4064)
			(end 0.7874 0.4064)
			(stroke
				(width 0.1524)
				(type default)
			)
			(layer "F.SilkS")
		)
		(fp_line
			(start -0.7874 -0.4064)
			(end 0.7874 -0.4064)
			(stroke
				(width 0.1524)
				(type default)
			)
			(layer "F.SilkS")
		)
		(fp_line
			(start 0.7874 0.4064)
			(end -0.7874 0.4064)
			(stroke
				(width 0.1524)
				(type default)
			)
			(layer "F.SilkS")
		)
		(fp_line
			(start -0.7874 0.4064)
			(end -0.7874 -0.4064)
			(stroke
				(width 0.1524)
				(type default)
			)
			(layer "F.SilkS")
		)
		(fp_line
			(start -0.12065 -0.305054)
			(end -0.12065 -0.2794)
			(stroke
				(width 0.1)
				(type default)
			)
			(layer "F.Fab")
		)
		(fp_line
			(start -0.67945 -0.305054)
			(end -0.12065 -0.305054)
			(stroke
				(width 0.1)
				(type default)
			)
			(layer "F.Fab")
		)
		(fp_line
			(start 0.67945 -0.3048)
			(end 0.67945 0.3048)
			(stroke
				(width 0.1)
				(type default)
			)
			(layer "F.Fab")
		)
		(fp_line
			(start 0.12065 -0.3048)
			(end 0.67945 -0.3048)
			(stroke
				(width 0.1)
				(type default)
			)
			(layer "F.Fab")
		)
		(fp_line
			(start 0.12065 -0.2794)
			(end 0.12065 -0.3048)
			(stroke
				(width 0.1)
				(type default)
			)
			(layer "F.Fab")
		)
		(fp_line
			(start -0.12065 -0.2794)
			(end 0.12065 -0.2794)
			(stroke
				(width 0.1)
				(type default)
			)
			(layer "F.Fab")
		)
		(fp_line
			(start 0.120396 0.2794)
			(end -0.12065 0.2794)
			(stroke
				(width 0.1)
				(type default)
			)
			(layer "F.Fab")
		)
		(fp_line
			(start -0.12065 0.2794)
			(end -0.12065 0.3048)
			(stroke
				(width 0.1)
				(type default)
			)
			(layer "F.Fab")
		)
		(fp_line
			(start 0.67945 0.3048)
			(end 0.120396 0.3048)
			(stroke
				(width 0.1)
				(type default)
			)
			(layer "F.Fab")
		)
		(fp_line
			(start 0.120396 0.3048)
			(end 0.120396 0.2794)
			(stroke
				(width 0.1)
				(type default)
			)
			(layer "F.Fab")
		)
		(fp_line
			(start -0.12065 0.3048)
			(end -0.67945 0.3048)
			(stroke
				(width 0.1)
				(type default)
			)
			(layer "F.Fab")
		)
		(fp_line
			(start -0.67945 0.3048)
			(end -0.67945 -0.305054)
			(stroke
				(width 0.1)
				(type default)
			)
			(layer "F.Fab")
		)
		(pad "1" smd circle
			(at -0.40005 0 90)
			(size 0 0)
			(layers "F.Cu" "F.Mask" "F.Paste")
			(net "P3V3_AUX")
		)
		(pad "2" smd circle
			(at 0.40005 0 90)
			(size 0 0)
			(layers "F.Cu" "F.Mask" "F.Paste")
			(net "UART_CPU0_SCM_LVC3_UART1_R_RX")
		)
	)
	(footprint ""
		(layer "F.Cu")
		(at 224.898712 -67.921378)
		(property "Reference" "R3973"
			(at 0 0 0)
			(layer "F.SilkS")
			(hide yes)
			(effects
				(font
					(size 1.27 1.27)
				)
			)
		)
		(property "Value" ""
			(at 0 0 0)
			(layer "F.Fab")
			(effects
				(font
					(size 1.27 1.27)
				)
			)
		)
		(duplicate_pad_numbers_are_jumpers no)
		(fp_line
			(start -0.7874 -0.4064)
			(end 0.7874 -0.4064)
			(stroke
				(width 0.1524)
				(type default)
			)
			(layer "F.SilkS")
		)
		(fp_line
			(start -0.7874 0.4064)
			(end -0.7874 -0.4064)
			(stroke
				(width 0.1524)
				(type default)
			)
			(layer "F.SilkS")
		)
		(fp_line
			(start 0.7874 -0.4064)
			(end 0.7874 0.4064)
			(stroke
				(width 0.1524)
				(type default)
			)
			(layer "F.SilkS")
		)
		(fp_line
			(start 0.7874 0.4064)
			(end -0.7874 0.4064)
			(stroke
				(width 0.1524)
				(type default)
			)
			(layer "F.SilkS")
		)
		(fp_line
			(start -0.67945 -0.305054)
			(end -0.12065 -0.305054)
			(stroke
				(width 0.1)
				(type default)
			)
			(layer "F.Fab")
		)
		(fp_line
			(start -0.67945 0.3048)
			(end -0.67945 -0.305054)
			(stroke
				(width 0.1)
				(type default)
			)
			(layer "F.Fab")
		)
		(fp_line
			(start -0.12065 -0.305054)
			(end -0.12065 -0.2794)
			(stroke
				(width 0.1)
				(type default)
			)
			(layer "F.Fab")
		)
		(fp_line
			(start -0.12065 -0.2794)
			(end 0.12065 -0.2794)
			(stroke
				(width 0.1)
				(type default)
			)
			(layer "F.Fab")
		)
		(fp_line
			(start -0.12065 0.2794)
			(end -0.12065 0.3048)
			(stroke
				(width 0.1)
				(type default)
			)
			(layer "F.Fab")
		)
		(fp_line
			(start -0.12065 0.3048)
			(end -0.67945 0.3048)
			(stroke
				(width 0.1)
				(type default)
			)
			(layer "F.Fab")
		)
		(fp_line
			(start 0.120396 0.2794)
			(end -0.12065 0.2794)
			(stroke
				(width 0.1)
				(type default)
			)
			(layer "F.Fab")
		)
		(fp_line
			(start 0.120396 0.3048)
			(end 0.120396 0.2794)
			(stroke
				(width 0.1)
				(type default)
			)
			(layer "F.Fab")
		)
		(fp_line
			(start 0.12065 -0.3048)
			(end 0.67945 -0.3048)
			(stroke
				(width 0.1)
				(type default)
			)
			(layer "F.Fab")
		)
		(fp_line
			(start 0.12065 -0.2794)
			(end 0.12065 -0.3048)
			(stroke
				(width 0.1)
				(type default)
			)
			(layer "F.Fab")
		)
		(fp_line
			(start 0.67945 -0.3048)
			(end 0.67945 0.3048)
			(stroke
				(width 0.1)
				(type default)
			)
			(layer "F.Fab")
		)
		(fp_line
			(start 0.67945 0.3048)
			(end 0.120396 0.3048)
			(stroke
				(width 0.1)
				(type default)
			)
			(layer "F.Fab")
		)
		(pad "1" smd circle
			(at -0.40005 0)
			(size 0 0)
			(layers "F.Cu" "F.Mask" "F.Paste")
			(net "P3V3_E1S_PWRGD_0")
		)
		(pad "2" smd circle
			(at 0.40005 0)
			(size 0 0)
			(layers "F.Cu" "F.Mask" "F.Paste")
			(net "P3V3_E1S_PWRGD_0_R")
		)
	)
	(footprint ""
		(layer "F.Cu")
		(at 114.197638 -395.221206 -90)
		(property "Reference" "R924"
			(at 0 0 270)
			(layer "F.SilkS")
			(hide yes)
			(effects
				(font
					(size 1.27 1.27)
				)
			)
		)
		(property "Value" ""
			(at 0 0 270)
			(layer "F.Fab")
			(effects
				(font
					(size 1.27 1.27)
				)
			)
		)
		(duplicate_pad_numbers_are_jumpers no)
		(fp_line
			(start -0.32512 0.175006)
			(end -0.32512 -0.175006)
			(stroke
				(width 0.1)
				(type default)
			)
			(layer "F.Fab")
		)
		(fp_line
			(start 0.32512 0.175006)
			(end -0.32512 0.175006)
			(stroke
				(width 0.1)
				(type default)
			)
			(layer "F.Fab")
		)
		(fp_line
			(start -0.32512 -0.175006)
			(end 0.32512 -0.175006)
			(stroke
				(width 0.1)
				(type default)
			)
			(layer "F.Fab")
		)
		(fp_line
			(start 0.32512 -0.175006)
			(end 0.32512 0.175006)
			(stroke
				(width 0.1)
				(type default)
			)
			(layer "F.Fab")
		)
		(pad "1" smd rect
			(at -0.2667 0 270)
			(size 0.3048 0.381)
			(layers "F.Cu" "F.Mask" "F.Paste")
			(net "JTAG_TEST_MODE_RT_CPU1_P3")
		)
		(pad "2" smd rect
			(at 0.2667 0 90)
			(size 0.3048 0.381)
			(layers "F.Cu" "F.Mask" "F.Paste")
			(net "GND")
		)
	)
)
